(kicad_pcb
	(version 20221018)
	(generator pcbnew)
	(general
    (thickness 1.62)
  )
	(paper "A4")
	(title_block
    (title "ECP5 - Datacenter Secure Control Module (DC-SCM)")
    (date "2024-07-01")
    (rev "1.2.1")
		(comment 9 "footprints 368-375 of 506")
	)
	(layers
    (0 "F.Cu" signal)
    (1 "In1.Cu" power)
    (2 "In2.Cu" signal)
    (3 "In3.Cu" power)
    (4 "In4.Cu" power)
    (5 "In5.Cu" signal)
    (6 "In6.Cu" power)
    (31 "B.Cu" signal)
    (32 "B.Adhes" user "B.Adhesive")
    (33 "F.Adhes" user "F.Adhesive")
    (34 "B.Paste" user)
    (35 "F.Paste" user)
    (36 "B.SilkS" user "B.Silkscreen")
    (37 "F.SilkS" user "F.Silkscreen")
    (38 "B.Mask" user)
    (39 "F.Mask" user)
    (40 "Dwgs.User" user "User.Drawings")
    (41 "Cmts.User" user "User.Comments")
    (42 "Eco1.User" user "User.Eco1")
    (43 "Eco2.User" user "User.Eco2")
    (44 "Edge.Cuts" user)
    (45 "Margin" user)
    (46 "B.CrtYd" user "B.Courtyard")
    (47 "F.CrtYd" user "F.Courtyard")
    (48 "B.Fab" user)
    (49 "F.Fab" user)
  )
	(footprint "antmicro-footprints:C_0402_1005Metric" (layer "B.Cu")
    (at 106.05 100.3 -90)
    (descr "Capacitor SMD 0402")
    (tags "capacitor SMD 0402")
    (property "Author" "Antmicro")
    (property "Dielectric" "X7R")
    (property "License" "Apache-2.0")
    (property "MPN" "GRM155R71H103KA88D")
    (property "Manufacturer" "Murata")
    (property "Public" "False")
    (property "Sheetfile" "ethernet.kicad_sch")
    (property "Sheetname" "Ethernet")
    (property "Val" "10n")
    (property "Voltage" "50V")
    (property "ki_description" "SMD Multilayer Ceramic Capacitor, 10000 pF, 50 V, 0402 [1005 Metric], ± 10%, X7R, GRM Series")
    (property "ki_keywords" "0402, SMT, CAPACITOR, PASSIVE")
    (attr smd)
    (fp_text reference "C17" (at 0.855 -0.85 90) (layer "B.SilkS")
        (effects (font (size 0.7 0.7) (thickness 0.127)) (justify mirror))
    )
    (fp_text value "C_10n_0402" (at 0 -1.17 90) (layer "B.Fab")
        (effects (font (size 1 1) (thickness 0.15)) (justify mirror))
    )
    (fp_text user "License: Apache-2.0" (at -0.939 -5.799 90) (layer "B.Fab") hide
        (effects (font (size 0.7 0.7) (thickness 0.15)) (justify left bottom mirror))
    )
    (fp_text user "${REFERENCE}" (at 0 0 90) (layer "B.Fab")
        (effects (font (size 0.25 0.25) (thickness 0.04)) (justify mirror))
    )
    (fp_text user "Author: Antmicro" (at -0.939 -3.399 90) (layer "B.Fab") hide
        (effects (font (size 0.7 0.7) (thickness 0.15)) (justify left bottom mirror))
    )
    (fp_rect (start -0.925 0.47) (end 0.925 -0.47)
      (stroke (width 0.05) (type default)) (fill none) (layer "B.CrtYd"))
    (fp_line (start -0.494 -0.248) (end -0.494 0.25)
      (stroke (width 0.15) (type solid)) (layer "B.Fab"))
    (fp_line (start -0.494 0.25) (end 0.504 0.25)
      (stroke (width 0.15) (type solid)) (layer "B.Fab"))
    (fp_line (start 0.504 -0.248) (end -0.494 -0.248)
      (stroke (width 0.15) (type solid)) (layer "B.Fab"))
    (fp_line (start 0.504 0.25) (end 0.504 -0.248)
      (stroke (width 0.15) (type solid)) (layer "B.Fab"))
    (pad "1" smd roundrect (at -0.48 0 270) (size 0.59 0.64) (layers "B.Cu" "B.Paste" "B.Mask") (roundrect_rratio 0.25)
      (net 1 "GND") (pintype "passive"))
    (pad "2" smd roundrect (at 0.48 0 270) (size 0.59 0.64) (layers "B.Cu" "B.Paste" "B.Mask") (roundrect_rratio 0.25)
      (net 2 "VCC3V3") (pintype "passive"))
  )
	(footprint "antmicro-footprints:C_0402_1005Metric" (layer "B.Cu")
    (at 105.95 93.35 90)
    (descr "Capacitor SMD 0402")
    (tags "capacitor SMD 0402")
    (property "Author" "Antmicro")
    (property "Dielectric" "X7R")
    (property "License" "Apache-2.0")
    (property "MPN" "GRM155R71H103KA88D")
    (property "Manufacturer" "Murata")
    (property "Public" "False")
    (property "Sheetfile" "ethernet.kicad_sch")
    (property "Sheetname" "Ethernet")
    (property "Val" "10n")
    (property "Voltage" "50V")
    (property "ki_description" "SMD Multilayer Ceramic Capacitor, 10000 pF, 50 V, 0402 [1005 Metric], ± 10%, X7R, GRM Series")
    (property "ki_keywords" "0402, SMT, CAPACITOR, PASSIVE")
    (attr smd)
    (fp_text reference "C16" (at 0.005 0.87 90) (layer "B.SilkS")
        (effects (font (size 0.7 0.7) (thickness 0.127)) (justify mirror))
    )
    (fp_text value "C_10n_0402" (at 0 -1.17 90) (layer "B.Fab")
        (effects (font (size 1 1) (thickness 0.15)) (justify mirror))
    )
    (fp_text user "License: Apache-2.0" (at -0.939 -5.799 270) (layer "B.Fab") hide
        (effects (font (size 0.7 0.7) (thickness 0.15)) (justify left bottom mirror))
    )
    (fp_text user "Author: Antmicro" (at -0.939 -3.399 270) (layer "B.Fab") hide
        (effects (font (size 0.7 0.7) (thickness 0.15)) (justify left bottom mirror))
    )
    (fp_text user "${REFERENCE}" (at 0 0 90) (layer "B.Fab")
        (effects (font (size 0.25 0.25) (thickness 0.04)) (justify mirror))
    )
    (fp_rect (start -0.925 0.47) (end 0.925 -0.47)
      (stroke (width 0.05) (type default)) (fill none) (layer "B.CrtYd"))
    (fp_line (start -0.494 -0.248) (end -0.494 0.25)
      (stroke (width 0.15) (type solid)) (layer "B.Fab"))
    (fp_line (start -0.494 0.25) (end 0.504 0.25)
      (stroke (width 0.15) (type solid)) (layer "B.Fab"))
    (fp_line (start 0.504 -0.248) (end -0.494 -0.248)
      (stroke (width 0.15) (type solid)) (layer "B.Fab"))
    (fp_line (start 0.504 0.25) (end 0.504 -0.248)
      (stroke (width 0.15) (type solid)) (layer "B.Fab"))
    (pad "1" smd roundrect (at -0.48 0 90) (size 0.59 0.64) (layers "B.Cu" "B.Paste" "B.Mask") (roundrect_rratio 0.25)
      (net 1 "GND") (pintype "passive"))
    (pad "2" smd roundrect (at 0.48 0 90) (size 0.59 0.64) (layers "B.Cu" "B.Paste" "B.Mask") (roundrect_rratio 0.25)
      (net 4 "/Ethernet/AVDDH") (pintype "passive"))
  )
	(footprint "antmicro-footprints:C_0402_1005Metric" (layer "B.Cu")
    (at 103.02 99.55 -90)
    (descr "Capacitor SMD 0402")
    (tags "capacitor SMD 0402")
    (property "Author" "Antmicro")
    (property "Dielectric" "X7R")
    (property "License" "Apache-2.0")
    (property "MPN" "GRM155R71H103KA88D")
    (property "Manufacturer" "Murata")
    (property "Public" "False")
    (property "Sheetfile" "ethernet.kicad_sch")
    (property "Sheetname" "Ethernet")
    (property "Val" "10n")
    (property "Voltage" "50V")
    (property "ki_description" "SMD Multilayer Ceramic Capacitor, 10000 pF, 50 V, 0402 [1005 Metric], ± 10%, X7R, GRM Series")
    (property "ki_keywords" "0402, SMT, CAPACITOR, PASSIVE")
    (attr smd)
    (fp_text reference "C15" (at -1.905 -0.01 90) (layer "B.SilkS")
        (effects (font (size 0.7 0.7) (thickness 0.127)) (justify mirror))
    )
    (fp_text value "C_10n_0402" (at 0 -1.17 90) (layer "B.Fab")
        (effects (font (size 1 1) (thickness 0.15)) (justify mirror))
    )
    (fp_text user "Author: Antmicro" (at -0.939 -3.399 90) (layer "B.Fab") hide
        (effects (font (size 0.7 0.7) (thickness 0.15)) (justify left bottom mirror))
    )
    (fp_text user "${REFERENCE}" (at 0 0 90) (layer "B.Fab")
        (effects (font (size 0.25 0.25) (thickness 0.04)) (justify mirror))
    )
    (fp_text user "License: Apache-2.0" (at -0.939 -5.799 90) (layer "B.Fab") hide
        (effects (font (size 0.7 0.7) (thickness 0.15)) (justify left bottom mirror))
    )
    (fp_rect (start -0.925 0.47) (end 0.925 -0.47)
      (stroke (width 0.05) (type default)) (fill none) (layer "B.CrtYd"))
    (fp_line (start -0.494 -0.248) (end -0.494 0.25)
      (stroke (width 0.15) (type solid)) (layer "B.Fab"))
    (fp_line (start -0.494 0.25) (end 0.504 0.25)
      (stroke (width 0.15) (type solid)) (layer "B.Fab"))
    (fp_line (start 0.504 -0.248) (end -0.494 -0.248)
      (stroke (width 0.15) (type solid)) (layer "B.Fab"))
    (fp_line (start 0.504 0.25) (end 0.504 -0.248)
      (stroke (width 0.15) (type solid)) (layer "B.Fab"))
    (pad "1" smd roundrect (at -0.48 0 270) (size 0.59 0.64) (layers "B.Cu" "B.Paste" "B.Mask") (roundrect_rratio 0.25)
      (net 1 "GND") (pintype "passive"))
    (pad "2" smd roundrect (at 0.48 0 270) (size 0.59 0.64) (layers "B.Cu" "B.Paste" "B.Mask") (roundrect_rratio 0.25)
      (net 211 "VCC1V2") (pintype "passive"))
  )
	(footprint "antmicro-footprints:C_0402_1005Metric" (layer "B.Cu")
    (at 108.95 97.75 180)
    (descr "Capacitor SMD 0402")
    (tags "capacitor SMD 0402")
    (property "Author" "Antmicro")
    (property "Dielectric" "X7R")
    (property "License" "Apache-2.0")
    (property "MPN" "GRM155R71H103KA88D")
    (property "Manufacturer" "Murata")
    (property "Public" "False")
    (property "Sheetfile" "ethernet.kicad_sch")
    (property "Sheetname" "Ethernet")
    (property "Val" "10n")
    (property "Voltage" "50V")
    (property "ki_description" "SMD Multilayer Ceramic Capacitor, 10000 pF, 50 V, 0402 [1005 Metric], ± 10%, X7R, GRM Series")
    (property "ki_keywords" "0402, SMT, CAPACITOR, PASSIVE")
    (attr smd)
    (fp_text reference "C14" (at -2.54 -0.005) (layer "B.SilkS")
        (effects (font (size 0.7 0.7) (thickness 0.127)) (justify mirror))
    )
    (fp_text value "C_10n_0402" (at 0 -1.17) (layer "B.Fab")
        (effects (font (size 1 1) (thickness 0.15)) (justify mirror))
    )
    (fp_text user "Author: Antmicro" (at -0.939 -3.399) (layer "B.Fab") hide
        (effects (font (size 0.7 0.7) (thickness 0.15)) (justify left bottom mirror))
    )
    (fp_text user "License: Apache-2.0" (at -0.939 -5.799) (layer "B.Fab") hide
        (effects (font (size 0.7 0.7) (thickness 0.15)) (justify left bottom mirror))
    )
    (fp_text user "${REFERENCE}" (at 0 0) (layer "B.Fab")
        (effects (font (size 0.25 0.25) (thickness 0.04)) (justify mirror))
    )
    (fp_rect (start -0.925 0.47) (end 0.925 -0.47)
      (stroke (width 0.05) (type default)) (fill none) (layer "B.CrtYd"))
    (fp_line (start -0.494 -0.248) (end -0.494 0.25)
      (stroke (width 0.15) (type solid)) (layer "B.Fab"))
    (fp_line (start -0.494 0.25) (end 0.504 0.25)
      (stroke (width 0.15) (type solid)) (layer "B.Fab"))
    (fp_line (start 0.504 -0.248) (end -0.494 -0.248)
      (stroke (width 0.15) (type solid)) (layer "B.Fab"))
    (fp_line (start 0.504 0.25) (end 0.504 -0.248)
      (stroke (width 0.15) (type solid)) (layer "B.Fab"))
    (pad "1" smd roundrect (at -0.48 0 180) (size 0.59 0.64) (layers "B.Cu" "B.Paste" "B.Mask") (roundrect_rratio 0.25)
      (net 1 "GND") (pintype "passive"))
    (pad "2" smd roundrect (at 0.48 0 180) (size 0.59 0.64) (layers "B.Cu" "B.Paste" "B.Mask") (roundrect_rratio 0.25)
      (net 2 "VCC3V3") (pintype "passive"))
  )
	(footprint "antmicro-footprints:C_0402_1005Metric" (layer "B.Cu")
    (at 105.95 90.55 -90)
    (descr "Capacitor SMD 0402")
    (tags "capacitor SMD 0402")
    (property "Author" "Antmicro")
    (property "Dielectric" "X7R")
    (property "License" "Apache-2.0")
    (property "MPN" "GRM155R71H103KA88D")
    (property "Manufacturer" "Murata")
    (property "Public" "False")
    (property "Sheetfile" "ethernet.kicad_sch")
    (property "Sheetname" "Ethernet")
    (property "Val" "10n")
    (property "Voltage" "50V")
    (property "ki_description" "SMD Multilayer Ceramic Capacitor, 10000 pF, 50 V, 0402 [1005 Metric], ± 10%, X7R, GRM Series")
    (property "ki_keywords" "0402, SMT, CAPACITOR, PASSIVE")
    (attr smd)
    (fp_text reference "C13" (at -0.005 -0.95 90) (layer "B.SilkS")
        (effects (font (size 0.7 0.7) (thickness 0.127)) (justify mirror))
    )
    (fp_text value "C_10n_0402" (at 0 -1.17 90) (layer "B.Fab")
        (effects (font (size 1 1) (thickness 0.15)) (justify mirror))
    )
    (fp_text user "Author: Antmicro" (at -0.939 -3.399 90) (layer "B.Fab") hide
        (effects (font (size 0.7 0.7) (thickness 0.15)) (justify left bottom mirror))
    )
    (fp_text user "License: Apache-2.0" (at -0.939 -5.799 90) (layer "B.Fab") hide
        (effects (font (size 0.7 0.7) (thickness 0.15)) (justify left bottom mirror))
    )
    (fp_text user "${REFERENCE}" (at 0 0 90) (layer "B.Fab")
        (effects (font (size 0.25 0.25) (thickness 0.04)) (justify mirror))
    )
    (fp_rect (start -0.925 0.47) (end 0.925 -0.47)
      (stroke (width 0.05) (type default)) (fill none) (layer "B.CrtYd"))
    (fp_line (start -0.494 -0.248) (end -0.494 0.25)
      (stroke (width 0.15) (type solid)) (layer "B.Fab"))
    (fp_line (start -0.494 0.25) (end 0.504 0.25)
      (stroke (width 0.15) (type solid)) (layer "B.Fab"))
    (fp_line (start 0.504 -0.248) (end -0.494 -0.248)
      (stroke (width 0.15) (type solid)) (layer "B.Fab"))
    (fp_line (start 0.504 0.25) (end 0.504 -0.248)
      (stroke (width 0.15) (type solid)) (layer "B.Fab"))
    (pad "1" smd roundrect (at -0.48 0 270) (size 0.59 0.64) (layers "B.Cu" "B.Paste" "B.Mask") (roundrect_rratio 0.25)
      (net 1 "GND") (pintype "passive"))
    (pad "2" smd roundrect (at 0.48 0 270) (size 0.59 0.64) (layers "B.Cu" "B.Paste" "B.Mask") (roundrect_rratio 0.25)
      (net 4 "/Ethernet/AVDDH") (pintype "passive"))
  )
	(footprint "antmicro-footprints:C_0402_1005Metric" (layer "B.Cu")
    (at 100.1 94.15 180)
    (descr "Capacitor SMD 0402")
    (tags "capacitor SMD 0402")
    (property "Author" "Antmicro")
    (property "Dielectric" "X7R")
    (property "License" "Apache-2.0")
    (property "MPN" "GRM155R71H103KA88D")
    (property "Manufacturer" "Murata")
    (property "Public" "False")
    (property "Sheetfile" "ethernet.kicad_sch")
    (property "Sheetname" "Ethernet")
    (property "Val" "10n")
    (property "Voltage" "50V")
    (property "ki_description" "SMD Multilayer Ceramic Capacitor, 10000 pF, 50 V, 0402 [1005 Metric], ± 10%, X7R, GRM Series")
    (property "ki_keywords" "0402, SMT, CAPACITOR, PASSIVE")
    (attr smd)
    (fp_text reference "C12" (at -0.04 0.945) (layer "B.SilkS")
        (effects (font (size 0.7 0.7) (thickness 0.127)) (justify mirror))
    )
    (fp_text value "C_10n_0402" (at 0 -1.17) (layer "B.Fab")
        (effects (font (size 1 1) (thickness 0.15)) (justify mirror))
    )
    (fp_text user "Author: Antmicro" (at -0.939 -3.399) (layer "B.Fab") hide
        (effects (font (size 0.7 0.7) (thickness 0.15)) (justify left bottom mirror))
    )
    (fp_text user "License: Apache-2.0" (at -0.939 -5.799) (layer "B.Fab") hide
        (effects (font (size 0.7 0.7) (thickness 0.15)) (justify left bottom mirror))
    )
    (fp_text user "${REFERENCE}" (at 0 0) (layer "B.Fab")
        (effects (font (size 0.25 0.25) (thickness 0.04)) (justify mirror))
    )
    (fp_rect (start -0.925 0.47) (end 0.925 -0.47)
      (stroke (width 0.05) (type default)) (fill none) (layer "B.CrtYd"))
    (fp_line (start -0.494 -0.248) (end -0.494 0.25)
      (stroke (width 0.15) (type solid)) (layer "B.Fab"))
    (fp_line (start -0.494 0.25) (end 0.504 0.25)
      (stroke (width 0.15) (type solid)) (layer "B.Fab"))
    (fp_line (start 0.504 -0.248) (end -0.494 -0.248)
      (stroke (width 0.15) (type solid)) (layer "B.Fab"))
    (fp_line (start 0.504 0.25) (end 0.504 -0.248)
      (stroke (width 0.15) (type solid)) (layer "B.Fab"))
    (pad "1" smd roundrect (at -0.48 0 180) (size 0.59 0.64) (layers "B.Cu" "B.Paste" "B.Mask") (roundrect_rratio 0.25)
      (net 1 "GND") (pintype "passive"))
    (pad "2" smd roundrect (at 0.48 0 180) (size 0.59 0.64) (layers "B.Cu" "B.Paste" "B.Mask") (roundrect_rratio 0.25)
      (net 211 "VCC1V2") (pintype "passive"))
  )
	(footprint "antmicro-footprints:C_0402_1005Metric" (layer "B.Cu")
    (at 100.45 90.55 -90)
    (descr "Capacitor SMD 0402")
    (tags "capacitor SMD 0402")
    (property "Author" "Antmicro")
    (property "Dielectric" "")
    (property "License" "Apache-2.0")
    (property "MPN" "GRM155R61A475MEAAD")
    (property "Manufacturer" "Murata")
    (property "Public" "False")
    (property "Sheetfile" "ethernet.kicad_sch")
    (property "Sheetname" "Ethernet")
    (property "Val" "4u7")
    (property "Voltage" "")
    (property "ki_description" "SMD Multilayer Ceramic Capacitor, 4.7 µF, 10 V, 0402 [1005 Metric], ± 20%, X5R, GRM Series")
    (property "ki_keywords" "0402, SMT, CAPACITOR, PASSIVE")
    (attr smd)
    (fp_text reference "C10" (at -0.045 0.94 90) (layer "B.SilkS")
        (effects (font (size 0.7 0.7) (thickness 0.127)) (justify mirror))
    )
    (fp_text value "C_4u7_0402" (at 0 -1.17 90) (layer "B.Fab")
        (effects (font (size 1 1) (thickness 0.15)) (justify mirror))
    )
    (fp_text user "Author: Antmicro" (at -0.939 -3.399 90) (layer "B.Fab") hide
        (effects (font (size 0.7 0.7) (thickness 0.15)) (justify left bottom mirror))
    )
    (fp_text user "${REFERENCE}" (at 0 0 90) (layer "B.Fab")
        (effects (font (size 0.25 0.25) (thickness 0.04)) (justify mirror))
    )
    (fp_text user "License: Apache-2.0" (at -0.939 -5.799 90) (layer "B.Fab") hide
        (effects (font (size 0.7 0.7) (thickness 0.15)) (justify left bottom mirror))
    )
    (fp_rect (start -0.925 0.47) (end 0.925 -0.47)
      (stroke (width 0.05) (type default)) (fill none) (layer "B.CrtYd"))
    (fp_line (start -0.494 -0.248) (end -0.494 0.25)
      (stroke (width 0.15) (type solid)) (layer "B.Fab"))
    (fp_line (start -0.494 0.25) (end 0.504 0.25)
      (stroke (width 0.15) (type solid)) (layer "B.Fab"))
    (fp_line (start 0.504 -0.248) (end -0.494 -0.248)
      (stroke (width 0.15) (type solid)) (layer "B.Fab"))
    (fp_line (start 0.504 0.25) (end 0.504 -0.248)
      (stroke (width 0.15) (type solid)) (layer "B.Fab"))
    (pad "1" smd roundrect (at -0.48 0 270) (size 0.59 0.64) (layers "B.Cu" "B.Paste" "B.Mask") (roundrect_rratio 0.25)
      (net 1 "GND") (pintype "passive"))
    (pad "2" smd roundrect (at 0.48 0 270) (size 0.59 0.64) (layers "B.Cu" "B.Paste" "B.Mask") (roundrect_rratio 0.25)
      (net 4 "/Ethernet/AVDDH") (pintype "passive"))
  )
	(footprint "antmicro-footprints:C_0402_1005Metric" (layer "B.Cu")
    (at 106.3 97.7)
    (descr "Capacitor SMD 0402")
    (tags "capacitor SMD 0402")
    (property "Author" "Antmicro")
    (property "Dielectric" "")
    (property "License" "Apache-2.0")
    (property "MPN" "C1005X5R1E474M050BB")
    (property "Manufacturer" "TDK")
    (property "Public" "False")
    (property "Sheetfile" "ethernet.kicad_sch")
    (property "Sheetname" "Ethernet")
    (property "Val" "470n")
    (property "Voltage" "")
    (property "ki_description" "SMD Multilayer Ceramic Capacitor, 0.47 µF, 25 V, 0402 [1005 Metric], ± 20%, X5R, C")
    (property "ki_keywords" "0402, SMT, CAPACITOR, PASSIVE, CERAMIC, MLCC")
    (attr smd)
    (fp_text reference "C8" (at 0.19 -0.835) (layer "B.SilkS")
        (effects (font (size 0.7 0.7) (thickness 0.127)) (justify mirror))
    )
    (fp_text value "C_470n_0402" (at 0 -1.17) (layer "B.Fab")
        (effects (font (size 1 1) (thickness 0.15)) (justify mirror))
    )
    (fp_text user "${REFERENCE}" (at 0 0) (layer "B.Fab")
        (effects (font (size 0.25 0.25) (thickness 0.04)) (justify mirror))
    )
    (fp_text user "Author: Antmicro" (at -0.939 -3.399 180) (layer "B.Fab") hide
        (effects (font (size 0.7 0.7) (thickness 0.15)) (justify left bottom mirror))
    )
    (fp_text user "License: Apache-2.0" (at -0.939 -5.799 180) (layer "B.Fab") hide
        (effects (font (size 0.7 0.7) (thickness 0.15)) (justify left bottom mirror))
    )
    (fp_rect (start -0.925 0.47) (end 0.925 -0.47)
      (stroke (width 0.05) (type default)) (fill none) (layer "B.CrtYd"))
    (fp_line (start -0.494 -0.248) (end -0.494 0.25)
      (stroke (width 0.15) (type solid)) (layer "B.Fab"))
    (fp_line (start -0.494 0.25) (end 0.504 0.25)
      (stroke (width 0.15) (type solid)) (layer "B.Fab"))
    (fp_line (start 0.504 -0.248) (end -0.494 -0.248)
      (stroke (width 0.15) (type solid)) (layer "B.Fab"))
    (fp_line (start 0.504 0.25) (end 0.504 -0.248)
      (stroke (width 0.15) (type solid)) (layer "B.Fab"))
    (pad "1" smd roundrect (at -0.48 0) (size 0.59 0.64) (layers "B.Cu" "B.Paste" "B.Mask") (roundrect_rratio 0.25)
      (net 1 "GND") (pintype "passive"))
    (pad "2" smd roundrect (at 0.48 0) (size 0.59 0.64) (layers "B.Cu" "B.Paste" "B.Mask") (roundrect_rratio 0.25)
      (net 2 "VCC3V3") (pintype "passive"))
  )
)
